# BASEBOARD_FAB2 (Tioga Pass) — schematic netlist excerpt (pin names and nets, part order shuffled) for the footprints in the layout excerpt that follows; sources: Cadence DE-HDL packaged netlist, KiCad conversion of Wiwynn_Tioga_Pass_MB.brd

RT48  1R3F-GP  1%  pkg RCL_GP  page 212 : \1\ = VR_PVCCIO_CPU0_PH1_SW_RC ; \2\ = GND
R12W25  RES  0.0 5% CHIP  pkg 0402  page 215 : A = PU_VR_PVDDQ_ABC_FAULT1 ; B = PWRGD_PVDDQ_ABC
C5A11  CAP_A  47UF 4V 20% X5R  pkg 0603V  page 220 : A = PVDDQ_DEF ; B = GND

(kicad_pcb
	(version 20260206)
	(generator "pcbnew")
	(generator_version "10.0")
	(general
		(thickness 1.6)
		(legacy_teardrops no)
	)
	(paper "A4")
	(title_block
		(title "Wiwynn_Tioga_Pass_MB.brd")
		(comment 1 "Tioga Pass / footprints 1344-1346 of 4770")
	)
	(layers
		(0 "F.Cu" signal "TOP")
		(4 "In1.Cu" signal "L2GND")
		(6 "In2.Cu" signal "L3")
		(8 "In3.Cu" signal "L4GND")
		(10 "In4.Cu" signal "L5")
		(12 "In5.Cu" signal "L6GND")
		(14 "In6.Cu" signal "L7VCC")
		(16 "In7.Cu" signal "L8VCC")
		(18 "In8.Cu" signal "L9GND")
		(20 "In9.Cu" signal "L10")
		(22 "In10.Cu" signal "L11GND")
		(24 "In11.Cu" signal "L12")
		(26 "In12.Cu" signal "L13GND")
		(2 "B.Cu" signal "BOTTOM")
		(9 "F.Adhes" user "F.Adhesive")
		(11 "B.Adhes" user "B.Adhesive")
		(13 "F.Paste" user "Package Geometry/Pastemask Top")
		(15 "B.Paste" user "Package Geometry/Pastemask Bottom")
		(5 "F.SilkS" user "Ref Des/Silkscreen Top")
		(7 "B.SilkS" user "Ref Des/Silkscreen Bottom")
		(1 "F.Mask" user "Board Geometry/Soldermask Top")
		(3 "B.Mask" user "Board Geometry/Soldermask Bottom")
		(17 "Dwgs.User" user "User.Drawings")
		(19 "Cmts.User" user "User.Comments")
		(21 "Eco1.User" user "User.Eco1")
		(23 "Eco2.User" user "User.Eco2")
		(25 "Edge.Cuts" user "Board Geometry/Outline")
		(27 "Margin" user)
		(31 "F.CrtYd" user "Package Geometry/Place Bound Top")
		(29 "B.CrtYd" user "Package Geometry/Place Bound Bottom")
		(35 "F.Fab" user "Ref Des/Assembly Top")
		(33 "B.Fab" user "Ref Des/Assembly Bottom")
	)
	(footprint ""
		(layer "F.Cu")
		(at 338.836 -18.923 -90)
		(property "Reference" "R12W25"
			(at -0.8382 -0.67818 270)
			(unlocked yes)
			(layer "F.SilkS")
			(effects
				(font
					(size 0.4064 0.254)
					(thickness 0.1524)
				)
				(justify left)
			)
		)
		(property "Value" ""
			(at 0 0 270)
			(layer "F.Fab")
			(effects
				(font
					(size 1.27 1.27)
				)
			)
		)
		(duplicate_pad_numbers_are_jumpers no)
		(fp_poly
			(pts
				(xy -0.2794 -0.1016) (xy 0.2794 -0.1016) (xy 0.2794 0.9906) (xy -0.2794 0.9906)
			)
			(stroke
				(width 0)
				(type default)
			)
			(fill no)
			(layer "F.CrtYd")
		)
		(fp_line
			(start -0.2794 0.9906)
			(end 0.2794 0.9906)
			(stroke
				(width 0.1)
				(type default)
			)
			(layer "F.Fab")
		)
		(fp_line
			(start 0.2794 0.9906)
			(end 0.2794 -0.1016)
			(stroke
				(width 0.1)
				(type default)
			)
			(layer "F.Fab")
		)
		(fp_line
			(start -0.2794 -0.1016)
			(end -0.2794 0.9906)
			(stroke
				(width 0.1)
				(type default)
			)
			(layer "F.Fab")
		)
		(fp_line
			(start 0.2794 -0.1016)
			(end -0.2794 -0.1016)
			(stroke
				(width 0.1)
				(type default)
			)
			(layer "F.Fab")
		)
		(pad "1" smd rect
			(at 0 0 270)
			(size 0.508 0.508)
			(layers "F.Cu" "F.Mask" "F.Paste")
			(net "PU_VR_PVDDQ_ABC_FAULT1")
		)
		(pad "2" smd rect
			(at 0 0.889 270)
			(size 0.508 0.508)
			(layers "F.Cu" "F.Mask" "F.Paste")
			(net "PWRGD_PVDDQ_ABC")
		)
		(zone
			(layer "F.Cu")
			(hatch none 0.5)
			(connect_pads
				(clearance 0)
			)
			(min_thickness 0.25)
			(keepout
				(tracks not_allowed)
				(vias allowed)
				(pads allowed)
				(copperpour not_allowed)
				(footprints allowed)
			)
			(placement
				(enabled no)
				(sheetname "")
			)
			(fill
				(thermal_gap 0.5)
				(thermal_bridge_width 0.5)
				(island_removal_mode 0)
			)
			(polygon
				(pts
					(xy 338.201 -19.177) (xy 338.201 -18.669) (xy 338.582 -18.669) (xy 338.582 -19.177)
				)
			)
		)
		(zone
			(layer "F.Cu")
			(hatch none 0.5)
			(connect_pads
				(clearance 0)
			)
			(min_thickness 0.25)
			(keepout
				(tracks allowed)
				(vias not_allowed)
				(pads allowed)
				(copperpour not_allowed)
				(footprints allowed)
			)
			(placement
				(enabled no)
				(sheetname "")
			)
			(fill
				(thermal_gap 0.5)
				(thermal_bridge_width 0.5)
				(island_removal_mode 0)
			)
			(polygon
				(pts
					(xy 338.582 -19.177) (xy 338.582 -18.669) (xy 338.201 -18.669) (xy 338.201 -19.177)
				)
			)
		)
	)
	(footprint ""
		(layer "F.Cu")
		(at 344.932 -93.5228 90)
		(property "Reference" "RT48"
			(at 0 0 90)
			(layer "F.SilkS")
			(hide yes)
			(effects
				(font
					(size 1.27 1.27)
				)
			)
		)
		(property "Value" "*"
			(at -0.0254 -2.6289 90)
			(unlocked yes)
			(layer "F.Fab")
			(hide yes)
			(effects
				(font
					(size 1.27 1.016)
					(thickness 0.1524)
				)
			)
		)
		(property "Device Type" "1R3F-GP_RCL_GP-1R3F-GP,64.1R00A"
			(at -0.0254 -4.1529 90)
			(unlocked yes)
			(layer "F.Fab")
			(hide yes)
			(effects
				(font
					(size 1.27 1.016)
					(thickness 0.1524)
				)
			)
		)
		(duplicate_pad_numbers_are_jumpers no)
		(fp_line
			(start 0.2032 0)
			(end 0.4826 0)
			(stroke
				(width 0.2032)
				(type default)
			)
			(layer "F.SilkS")
		)
		(fp_line
			(start -0.4826 0)
			(end -0.2032 0)
			(stroke
				(width 0.2032)
				(type default)
			)
			(layer "F.SilkS")
		)
		(fp_rect
			(start -0.5842 1.3335)
			(end 0.5842 -1.3335)
			(stroke
				(width 0)
				(type default)
			)
			(fill no)
			(layer "F.CrtYd")
		)
		(fp_rect
			(start -0.5842 1.3335)
			(end 0.5842 -1.3335)
			(stroke
				(width 0)
				(type default)
			)
			(fill no)
			(layer "F.Fab")
		)
		(pad "1" smd custom
			(at 0 -0.762 90)
			(size 0.2159 0.2159)
			(layers "F.Cu" "F.Mask" "F.Paste")
			(net "VR_PVCCIO_CPU0_PH1_SW_RC")
			(options
				(clearance outline)
				(anchor circle)
			)
			(primitives
				(gr_poly
					(pts
						(arc
							(start -0.3302 -0.4318)
							(mid -0.402042 -0.402042)
							(end -0.4318 -0.3302)
						)
						(arc
							(start -0.4318 0.3302)
							(mid -0.402042 0.402042)
							(end -0.3302 0.4318)
						)
						(arc
							(start 0.3302 0.4318)
							(mid 0.402042 0.402042)
							(end 0.4318 0.3302)
						)
						(arc
							(start 0.4318 -0.3302)
							(mid 0.402042 -0.402042)
							(end 0.3302 -0.4318)
						)
					)
					(width 0)
					(fill yes)
				)
			)
		)
		(pad "2" smd custom
			(at 0 0.762 90)
			(size 0.2159 0.2159)
			(layers "F.Cu" "F.Mask" "F.Paste")
			(net "GND")
			(options
				(clearance outline)
				(anchor circle)
			)
			(primitives
				(gr_poly
					(pts
						(arc
							(start -0.3302 -0.4318)
							(mid -0.402042 -0.402042)
							(end -0.4318 -0.3302)
						)
						(arc
							(start -0.4318 0.3302)
							(mid -0.402042 0.402042)
							(end -0.3302 0.4318)
						)
						(arc
							(start 0.3302 0.4318)
							(mid 0.402042 0.402042)
							(end 0.4318 0.3302)
						)
						(arc
							(start 0.4318 -0.3302)
							(mid 0.402042 -0.402042)
							(end 0.3302 -0.4318)
						)
					)
					(width 0)
					(fill yes)
				)
			)
		)
	)
	(footprint ""
		(layer "F.Cu")
		(at 245.7323 -140.208 -90)
		(property "Reference" "C5A11"
			(at 1.848866 0.752348 270)
			(unlocked yes)
			(layer "F.SilkS")
			(effects
				(font
					(size 1.27 0.9652)
					(thickness 0.1524)
				)
			)
		)
		(property "Value" ""
			(at 0 0 270)
			(layer "F.Fab")
			(effects
				(font
					(size 1.27 1.27)
				)
			)
		)
		(duplicate_pad_numbers_are_jumpers no)
		(fp_rect
			(start -0.500126 1.598422)
			(end 0.500126 -0.201422)
			(stroke
				(width 0)
				(type default)
			)
			(fill no)
			(layer "F.CrtYd")
		)
		(fp_line
			(start -0.500126 1.598422)
			(end -0.500126 -0.201422)
			(stroke
				(width 0.1)
				(type default)
			)
			(layer "F.Fab")
		)
		(fp_line
			(start 0.500126 1.598422)
			(end -0.500126 1.598422)
			(stroke
				(width 0.1)
				(type default)
			)
			(layer "F.Fab")
		)
		(fp_line
			(start -0.500126 -0.201422)
			(end 0.500126 -0.201422)
			(stroke
				(width 0.1)
				(type default)
			)
			(layer "F.Fab")
		)
		(fp_line
			(start 0.500126 -0.201422)
			(end 0.500126 1.598422)
			(stroke
				(width 0.1)
				(type default)
			)
			(layer "F.Fab")
		)
		(pad "1" smd rect
			(at 0 0 180)
			(size 0.889 0.9906)
			(layers "F.Cu" "F.Mask" "F.Paste")
			(net "PVDDQ_DEF")
		)
		(pad "2" smd rect
			(at 0 1.397 180)
			(size 0.889 0.9906)
			(layers "F.Cu" "F.Mask" "F.Paste")
			(net "GND")
		)
		(zone
			(layer "F.Cu")
			(hatch none 0.5)
			(connect_pads
				(clearance 0)
			)
			(min_thickness 0.25)
			(keepout
				(tracks not_allowed)
				(vias allowed)
				(pads allowed)
				(copperpour not_allowed)
				(footprints allowed)
			)
			(placement
				(enabled no)
				(sheetname "")
			)
			(fill
				(thermal_gap 0.5)
				(thermal_bridge_width 0.5)
				(island_removal_mode 0)
			)
			(polygon
				(pts
					(xy 244.7798 -140.7033) (xy 244.7798 -139.7127) (xy 245.2878 -139.7127) (xy 245.2878 -140.7033)
				)
			)
		)
		(zone
			(layer "F.Cu")
			(hatch none 0.5)
			(connect_pads
				(clearance 0)
			)
			(min_thickness 0.25)
			(keepout
				(tracks allowed)
				(vias not_allowed)
				(pads allowed)
				(copperpour not_allowed)
				(footprints allowed)
			)
			(placement
				(enabled no)
				(sheetname "")
			)
			(fill
				(thermal_gap 0.5)
				(thermal_bridge_width 0.5)
				(island_removal_mode 0)
			)
			(polygon
				(pts
					(xy 244.7798 -140.7033) (xy 244.7798 -139.7127) (xy 245.2878 -139.7127) (xy 245.2878 -140.7033)
				)
			)
		)
	)
)
